# T6G (Grand Teton) — schematic netlist excerpt (pin names and nets, part order shuffled) for the footprints in the layout excerpt that follows; sources: Cadence DE-HDL packaged netlist, KiCad conversion of 04192023_DAF0TMB3IC0_F0TG_MB_C_brd_V02_OCP.brd

PC385_2  Q_CAP  22UF 16V 20% X6S  pkg C0805  page 218 : A = SW_P12V_AUX_PVDDCR_CPU1_P1_FLT ; B = GND
PC635_3  Q_CAP  22UF 4V 20% X6S  pkg C0805  page 223 : A = PVDDIO_P1 ; B = GND
R1221  Q_RES  18K 1% CHIP  pkg 0402LF  page 258 : A = P1V2_AUX_ADC ; B = GND
C6609  Q_CAP_DIFFBUS  DIFF BUS_0.22UF 6.3V 20% X6S  pkg C0201  page 308 : \1\ = P5E_CPU0_P3_TX_BUF_C_DP<6> ; \2\ = P5E_CPU0_P3_TX_BUF_DP<6>

(kicad_pcb
	(version 20260206)
	(generator "pcbnew")
	(generator_version "10.0")
	(general
		(thickness 1.6)
		(legacy_teardrops no)
	)
	(paper "A4")
	(title_block
		(title "04192023_DAF0TMB3IC0_F0TG_MB_C_brd_V02_OCP.brd")
		(comment 1 "Grand Teton / footprints 5167-5170 of 8354")
	)
	(layers
		(0 "F.Cu" signal "TOP")
		(4 "In1.Cu" signal "GND")
		(6 "In2.Cu" signal "IN1")
		(8 "In3.Cu" signal "GND1")
		(10 "In4.Cu" signal "IN2")
		(12 "In5.Cu" signal "GND2")
		(14 "In6.Cu" signal "IN3")
		(16 "In7.Cu" signal "GND3")
		(18 "In8.Cu" signal "VCC")
		(20 "In9.Cu" signal "VCC1")
		(22 "In10.Cu" signal "GND4")
		(24 "In11.Cu" signal "IN4")
		(26 "In12.Cu" signal "GND5")
		(28 "In13.Cu" signal "IN5")
		(30 "In14.Cu" signal "GND6")
		(32 "In15.Cu" signal "IN6")
		(34 "In16.Cu" signal "GND7")
		(2 "B.Cu" signal "BOTTOM")
		(9 "F.Adhes" user "F.Adhesive")
		(11 "B.Adhes" user "B.Adhesive")
		(13 "F.Paste" user "Package Geometry/Pastemask Top")
		(15 "B.Paste" user "Package Geometry/Pastemask Bottom")
		(5 "F.SilkS" user "Ref Des/Silkscreen Top")
		(7 "B.SilkS" user "Ref Des/Silkscreen Bottom")
		(1 "F.Mask" user "Board Geometry/Soldermask Top")
		(3 "B.Mask" user "Board Geometry/Soldermask Bottom")
		(17 "Dwgs.User" user "User.Drawings")
		(19 "Cmts.User" user "User.Comments")
		(21 "Eco1.User" user "User.Eco1")
		(23 "Eco2.User" user "User.Eco2")
		(25 "Edge.Cuts" user "Board Geometry/Outline")
		(27 "Margin" user)
		(31 "F.CrtYd" user "Package Geometry/Place Bound Top")
		(29 "B.CrtYd" user "Package Geometry/Place Bound Bottom")
		(35 "F.Fab" user "Ref Des/Assembly Top")
		(33 "B.Fab" user "Ref Des/Assembly Bottom")
	)
	(footprint ""
		(layer "B.Cu")
		(at 234.81157 -323.746114 180)
		(property "Reference" "R1221"
			(at 0 0 0)
			(layer "B.SilkS")
			(hide yes)
			(effects
				(font
					(size 1.27 1.27)
				)
				(justify mirror)
			)
		)
		(property "Value" ""
			(at 0 0 0)
			(layer "B.Fab")
			(effects
				(font
					(size 1.27 1.27)
				)
				(justify mirror)
			)
		)
		(duplicate_pad_numbers_are_jumpers no)
		(fp_line
			(start 0.7874 0.4064)
			(end 0.7874 -0.4064)
			(stroke
				(width 0.1524)
				(type default)
			)
			(layer "B.SilkS")
		)
		(fp_line
			(start 0.7874 -0.4064)
			(end -0.7874 -0.4064)
			(stroke
				(width 0.1524)
				(type default)
			)
			(layer "B.SilkS")
		)
		(fp_line
			(start -0.7874 0.4064)
			(end 0.7874 0.4064)
			(stroke
				(width 0.1524)
				(type default)
			)
			(layer "B.SilkS")
		)
		(fp_line
			(start -0.7874 -0.4064)
			(end -0.7874 0.4064)
			(stroke
				(width 0.1524)
				(type default)
			)
			(layer "B.SilkS")
		)
		(fp_line
			(start 0.67945 0.3048)
			(end 0.67945 -0.305054)
			(stroke
				(width 0.1)
				(type default)
			)
			(layer "B.Fab")
		)
		(fp_line
			(start 0.67945 -0.305054)
			(end 0.12065 -0.305054)
			(stroke
				(width 0.1)
				(type default)
			)
			(layer "B.Fab")
		)
		(fp_line
			(start 0.12065 0.3048)
			(end 0.67945 0.3048)
			(stroke
				(width 0.1)
				(type default)
			)
			(layer "B.Fab")
		)
		(fp_line
			(start 0.12065 0.2794)
			(end 0.12065 0.3048)
			(stroke
				(width 0.1)
				(type default)
			)
			(layer "B.Fab")
		)
		(fp_line
			(start 0.12065 -0.2794)
			(end -0.12065 -0.2794)
			(stroke
				(width 0.1)
				(type default)
			)
			(layer "B.Fab")
		)
		(fp_line
			(start 0.12065 -0.305054)
			(end 0.12065 -0.2794)
			(stroke
				(width 0.1)
				(type default)
			)
			(layer "B.Fab")
		)
		(fp_line
			(start -0.120396 0.3048)
			(end -0.120396 0.2794)
			(stroke
				(width 0.1)
				(type default)
			)
			(layer "B.Fab")
		)
		(fp_line
			(start -0.120396 0.2794)
			(end 0.12065 0.2794)
			(stroke
				(width 0.1)
				(type default)
			)
			(layer "B.Fab")
		)
		(fp_line
			(start -0.12065 -0.2794)
			(end -0.12065 -0.3048)
			(stroke
				(width 0.1)
				(type default)
			)
			(layer "B.Fab")
		)
		(fp_line
			(start -0.12065 -0.3048)
			(end -0.67945 -0.3048)
			(stroke
				(width 0.1)
				(type default)
			)
			(layer "B.Fab")
		)
		(fp_line
			(start -0.67945 0.3048)
			(end -0.120396 0.3048)
			(stroke
				(width 0.1)
				(type default)
			)
			(layer "B.Fab")
		)
		(fp_line
			(start -0.67945 -0.3048)
			(end -0.67945 0.3048)
			(stroke
				(width 0.1)
				(type default)
			)
			(layer "B.Fab")
		)
		(pad "1" smd circle
			(at 0.40005 0)
			(size 0 0)
			(layers "B.Cu" "B.Mask" "B.Paste")
			(net "P1V2_AUX_ADC")
		)
		(pad "2" smd circle
			(at -0.40005 0)
			(size 0 0)
			(layers "B.Cu" "B.Mask" "B.Paste")
			(net "GND")
		)
	)
	(footprint ""
		(layer "B.Cu")
		(at 34.034476 -338.010754 -90)
		(property "Reference" "PC635_3"
			(at 0 0 90)
			(layer "B.SilkS")
			(hide yes)
			(effects
				(font
					(size 1.27 1.27)
				)
				(justify mirror)
			)
		)
		(property "Value" ""
			(at 0 0 90)
			(layer "B.Fab")
			(effects
				(font
					(size 1.27 1.27)
				)
				(justify mirror)
			)
		)
		(duplicate_pad_numbers_are_jumpers no)
		(fp_line
			(start -1.524 0.762)
			(end 1.524 0.762)
			(stroke
				(width 0.1524)
				(type default)
			)
			(layer "B.SilkS")
		)
		(fp_line
			(start 1.524 0.762)
			(end 1.524 -0.762)
			(stroke
				(width 0.1524)
				(type default)
			)
			(layer "B.SilkS")
		)
		(fp_line
			(start -1.524 -0.762)
			(end -1.524 0.762)
			(stroke
				(width 0.1524)
				(type default)
			)
			(layer "B.SilkS")
		)
		(fp_line
			(start 1.524 -0.762)
			(end -1.524 -0.762)
			(stroke
				(width 0.1524)
				(type default)
			)
			(layer "B.SilkS")
		)
		(fp_line
			(start -1.1049 0.724916)
			(end -1.1049 -0.724916)
			(stroke
				(width 0.1)
				(type default)
			)
			(layer "B.Fab")
		)
		(fp_line
			(start 1.1049 0.724916)
			(end -1.1049 0.724916)
			(stroke
				(width 0.1)
				(type default)
			)
			(layer "B.Fab")
		)
		(fp_line
			(start -1.1049 -0.724916)
			(end 1.1049 -0.724916)
			(stroke
				(width 0.1)
				(type default)
			)
			(layer "B.Fab")
		)
		(fp_line
			(start 1.1049 -0.724916)
			(end 1.1049 0.724916)
			(stroke
				(width 0.1)
				(type default)
			)
			(layer "B.Fab")
		)
		(pad "1" smd rect
			(at 0.889 0 270)
			(size 1.016 1.27)
			(layers "B.Cu" "B.Mask" "B.Paste")
			(net "PVDDIO_P1")
		)
		(pad "2" smd rect
			(at -0.889 0 270)
			(size 1.016 1.27)
			(layers "B.Cu" "B.Mask" "B.Paste")
			(net "GND")
		)
	)
	(footprint ""
		(layer "B.Cu")
		(at 391.694162 -416.899344 90)
		(property "Reference" "C6609"
			(at 0 0 90)
			(layer "B.SilkS")
			(hide yes)
			(effects
				(font
					(size 1.27 1.27)
				)
				(justify mirror)
			)
		)
		(property "Value" ""
			(at 0 0 90)
			(layer "B.Fab")
			(effects
				(font
					(size 1.27 1.27)
				)
				(justify mirror)
			)
		)
		(duplicate_pad_numbers_are_jumpers no)
		(fp_line
			(start 0.299974 -0.150114)
			(end -0.299974 -0.150114)
			(stroke
				(width 0.1)
				(type default)
			)
			(layer "B.Fab")
		)
		(fp_line
			(start -0.299974 -0.150114)
			(end -0.299974 0.150114)
			(stroke
				(width 0.1)
				(type default)
			)
			(layer "B.Fab")
		)
		(fp_line
			(start 0.299974 0.150114)
			(end 0.299974 -0.150114)
			(stroke
				(width 0.1)
				(type default)
			)
			(layer "B.Fab")
		)
		(fp_line
			(start -0.299974 0.150114)
			(end 0.299974 0.150114)
			(stroke
				(width 0.1)
				(type default)
			)
			(layer "B.Fab")
		)
		(pad "1" smd rect
			(at 0.2667 0 270)
			(size 0.3048 0.381)
			(layers "B.Cu" "B.Mask" "B.Paste")
			(net "P5E_CPU0_P3_TX_BUF_C_DP<6>")
		)
		(pad "2" smd rect
			(at -0.2667 0 270)
			(size 0.3048 0.381)
			(layers "B.Cu" "B.Mask" "B.Paste")
			(net "P5E_CPU0_P3_TX_BUF_DP<6>")
		)
	)
	(footprint ""
		(layer "B.Cu")
		(at 79.886302 -338.93252 -90)
		(property "Reference" "PC385_2"
			(at 0 0 90)
			(layer "B.SilkS")
			(hide yes)
			(effects
				(font
					(size 1.27 1.27)
				)
				(justify mirror)
			)
		)
		(property "Value" ""
			(at 0 0 90)
			(layer "B.Fab")
			(effects
				(font
					(size 1.27 1.27)
				)
				(justify mirror)
			)
		)
		(duplicate_pad_numbers_are_jumpers no)
		(fp_line
			(start -1.524 0.762)
			(end 1.524 0.762)
			(stroke
				(width 0.1524)
				(type default)
			)
			(layer "B.SilkS")
		)
		(fp_line
			(start 1.524 0.762)
			(end 1.524 -0.762)
			(stroke
				(width 0.1524)
				(type default)
			)
			(layer "B.SilkS")
		)
		(fp_line
			(start -1.524 -0.762)
			(end -1.524 0.762)
			(stroke
				(width 0.1524)
				(type default)
			)
			(layer "B.SilkS")
		)
		(fp_line
			(start 1.524 -0.762)
			(end -1.524 -0.762)
			(stroke
				(width 0.1524)
				(type default)
			)
			(layer "B.SilkS")
		)
		(fp_line
			(start -1.1049 0.724916)
			(end -1.1049 -0.724916)
			(stroke
				(width 0.1)
				(type default)
			)
			(layer "B.Fab")
		)
		(fp_line
			(start 1.1049 0.724916)
			(end -1.1049 0.724916)
			(stroke
				(width 0.1)
				(type default)
			)
			(layer "B.Fab")
		)
		(fp_line
			(start -1.1049 -0.724916)
			(end 1.1049 -0.724916)
			(stroke
				(width 0.1)
				(type default)
			)
			(layer "B.Fab")
		)
		(fp_line
			(start 1.1049 -0.724916)
			(end 1.1049 0.724916)
			(stroke
				(width 0.1)
				(type default)
			)
			(layer "B.Fab")
		)
		(pad "1" smd rect
			(at 0.889 0 270)
			(size 1.016 1.27)
			(layers "B.Cu" "B.Mask" "B.Paste")
			(net "SW_P12V_AUX_PVDDCR_CPU1_P1_FLT")
		)
		(pad "2" smd rect
			(at -0.889 0 270)
			(size 1.016 1.27)
			(layers "B.Cu" "B.Mask" "B.Paste")
			(net "GND")
		)
	)
)
